# SCM (Grand Teton) — schematic netlist excerpt (pin names and nets, part order shuffled) for the footprints in the layout excerpt that follows; sources: Cadence DE-HDL packaged netlist, KiCad conversion of 12092022_DA0F0TMDCD0_F0T_Management_Board_D_brd_V3_OCP.brd

R601  Q_RES  750 1% CHIP  pkg 0402LF  page 47 : A = LED_POSTCODE_3 ; B = LED_POSTCODE_3_R
R461  Q_RES  33.2 1% CHIP  pkg 0402LF  page 13 : A = BMC_ID_BEEP_SEL ; B = BMC_ID_BEEP_SEL_R1

(kicad_pcb
	(version 20260206)
	(generator "pcbnew")
	(generator_version "10.0")
	(general
		(thickness 1.6)
		(legacy_teardrops no)
	)
	(paper "A4")
	(title_block
		(title "12092022_DA0F0TMDCD0_F0T_Management_Board_D_brd_V3_OCP.brd")
		(comment 1 "Grand Teton / footprints 309-310 of 1440")
	)
	(layers
		(0 "F.Cu" signal "TOP")
		(4 "In1.Cu" signal "GND")
		(6 "In2.Cu" signal "IN1")
		(8 "In3.Cu" signal "GND1")
		(10 "In4.Cu" signal "IN2")
		(12 "In5.Cu" signal "VCC")
		(14 "In6.Cu" signal "VCC1")
		(16 "In7.Cu" signal "IN3")
		(18 "In8.Cu" signal "GND2")
		(20 "In9.Cu" signal "IN4")
		(22 "In10.Cu" signal "GND3")
		(2 "B.Cu" signal "BOTTOM")
		(9 "F.Adhes" user "F.Adhesive")
		(11 "B.Adhes" user "B.Adhesive")
		(13 "F.Paste" user "Package Geometry/Pastemask Top")
		(15 "B.Paste" user "Package Geometry/Pastemask Bottom")
		(5 "F.SilkS" user "Ref Des/Silkscreen Top")
		(7 "B.SilkS" user "Ref Des/Silkscreen Bottom")
		(1 "F.Mask" user "Board Geometry/Soldermask Top")
		(3 "B.Mask" user "Board Geometry/Soldermask Bottom")
		(17 "Dwgs.User" user "User.Drawings")
		(19 "Cmts.User" user "User.Comments")
		(21 "Eco1.User" user "User.Eco1")
		(23 "Eco2.User" user "User.Eco2")
		(25 "Edge.Cuts" user "Board Geometry/Outline")
		(27 "Margin" user)
		(31 "F.CrtYd" user "Package Geometry/Place Bound Top")
		(29 "B.CrtYd" user "Package Geometry/Place Bound Bottom")
		(35 "F.Fab" user "Ref Des/Assembly Top")
		(33 "B.Fab" user "Ref Des/Assembly Bottom")
	)
	(footprint ""
		(layer "F.Cu")
		(at 47.6377 -66.35496 -90)
		(property "Reference" "R461"
			(at 0 0 270)
			(layer "F.SilkS")
			(hide yes)
			(effects
				(font
					(size 1.27 1.27)
				)
			)
		)
		(property "Value" ""
			(at 0 0 270)
			(layer "F.Fab")
			(effects
				(font
					(size 1.27 1.27)
				)
			)
		)
		(duplicate_pad_numbers_are_jumpers no)
		(fp_line
			(start -0.7874 0.4064)
			(end -0.7874 -0.4064)
			(stroke
				(width 0.1524)
				(type default)
			)
			(layer "F.SilkS")
		)
		(fp_line
			(start 0.7874 0.4064)
			(end -0.7874 0.4064)
			(stroke
				(width 0.1524)
				(type default)
			)
			(layer "F.SilkS")
		)
		(fp_line
			(start -0.7874 -0.4064)
			(end 0.7874 -0.4064)
			(stroke
				(width 0.1524)
				(type default)
			)
			(layer "F.SilkS")
		)
		(fp_line
			(start 0.7874 -0.4064)
			(end 0.7874 0.4064)
			(stroke
				(width 0.1524)
				(type default)
			)
			(layer "F.SilkS")
		)
		(fp_line
			(start -0.67945 0.3048)
			(end -0.67945 -0.305054)
			(stroke
				(width 0.1)
				(type default)
			)
			(layer "F.Fab")
		)
		(fp_line
			(start -0.12065 0.3048)
			(end -0.67945 0.3048)
			(stroke
				(width 0.1)
				(type default)
			)
			(layer "F.Fab")
		)
		(fp_line
			(start 0.120396 0.3048)
			(end 0.120396 0.2794)
			(stroke
				(width 0.1)
				(type default)
			)
			(layer "F.Fab")
		)
		(fp_line
			(start 0.67945 0.3048)
			(end 0.120396 0.3048)
			(stroke
				(width 0.1)
				(type default)
			)
			(layer "F.Fab")
		)
		(fp_line
			(start -0.12065 0.2794)
			(end -0.12065 0.3048)
			(stroke
				(width 0.1)
				(type default)
			)
			(layer "F.Fab")
		)
		(fp_line
			(start 0.120396 0.2794)
			(end -0.12065 0.2794)
			(stroke
				(width 0.1)
				(type default)
			)
			(layer "F.Fab")
		)
		(fp_line
			(start -0.12065 -0.2794)
			(end 0.12065 -0.2794)
			(stroke
				(width 0.1)
				(type default)
			)
			(layer "F.Fab")
		)
		(fp_line
			(start 0.12065 -0.2794)
			(end 0.12065 -0.3048)
			(stroke
				(width 0.1)
				(type default)
			)
			(layer "F.Fab")
		)
		(fp_line
			(start 0.12065 -0.3048)
			(end 0.67945 -0.3048)
			(stroke
				(width 0.1)
				(type default)
			)
			(layer "F.Fab")
		)
		(fp_line
			(start 0.67945 -0.3048)
			(end 0.67945 0.3048)
			(stroke
				(width 0.1)
				(type default)
			)
			(layer "F.Fab")
		)
		(fp_line
			(start -0.67945 -0.305054)
			(end -0.12065 -0.305054)
			(stroke
				(width 0.1)
				(type default)
			)
			(layer "F.Fab")
		)
		(fp_line
			(start -0.12065 -0.305054)
			(end -0.12065 -0.2794)
			(stroke
				(width 0.1)
				(type default)
			)
			(layer "F.Fab")
		)
		(pad "1" smd circle
			(at -0.40005 0 270)
			(size 0 0)
			(layers "F.Cu" "F.Mask" "F.Paste")
			(net "BMC_ID_BEEP_SEL")
		)
		(pad "2" smd circle
			(at 0.40005 0 270)
			(size 0 0)
			(layers "F.Cu" "F.Mask" "F.Paste")
			(net "BMC_ID_BEEP_SEL_R1")
		)
	)
	(footprint ""
		(layer "F.Cu")
		(at 73.787 -25.5016 180)
		(property "Reference" "R601"
			(at 0 0 180)
			(layer "F.SilkS")
			(hide yes)
			(effects
				(font
					(size 1.27 1.27)
				)
			)
		)
		(property "Value" ""
			(at 0 0 180)
			(layer "F.Fab")
			(effects
				(font
					(size 1.27 1.27)
				)
			)
		)
		(duplicate_pad_numbers_are_jumpers no)
		(fp_line
			(start 0.7874 0.4064)
			(end -0.7874 0.4064)
			(stroke
				(width 0.1524)
				(type default)
			)
			(layer "F.SilkS")
		)
		(fp_line
			(start 0.7874 -0.4064)
			(end 0.7874 0.4064)
			(stroke
				(width 0.1524)
				(type default)
			)
			(layer "F.SilkS")
		)
		(fp_line
			(start -0.7874 0.4064)
			(end -0.7874 -0.4064)
			(stroke
				(width 0.1524)
				(type default)
			)
			(layer "F.SilkS")
		)
		(fp_line
			(start -0.7874 -0.4064)
			(end 0.7874 -0.4064)
			(stroke
				(width 0.1524)
				(type default)
			)
			(layer "F.SilkS")
		)
		(fp_line
			(start 0.67945 0.3048)
			(end 0.120396 0.3048)
			(stroke
				(width 0.1)
				(type default)
			)
			(layer "F.Fab")
		)
		(fp_line
			(start 0.67945 -0.3048)
			(end 0.67945 0.3048)
			(stroke
				(width 0.1)
				(type default)
			)
			(layer "F.Fab")
		)
		(fp_line
			(start 0.12065 -0.2794)
			(end 0.12065 -0.3048)
			(stroke
				(width 0.1)
				(type default)
			)
			(layer "F.Fab")
		)
		(fp_line
			(start 0.12065 -0.3048)
			(end 0.67945 -0.3048)
			(stroke
				(width 0.1)
				(type default)
			)
			(layer "F.Fab")
		)
		(fp_line
			(start 0.120396 0.3048)
			(end 0.120396 0.2794)
			(stroke
				(width 0.1)
				(type default)
			)
			(layer "F.Fab")
		)
		(fp_line
			(start 0.120396 0.2794)
			(end -0.12065 0.2794)
			(stroke
				(width 0.1)
				(type default)
			)
			(layer "F.Fab")
		)
		(fp_line
			(start -0.12065 0.3048)
			(end -0.67945 0.3048)
			(stroke
				(width 0.1)
				(type default)
			)
			(layer "F.Fab")
		)
		(fp_line
			(start -0.12065 0.2794)
			(end -0.12065 0.3048)
			(stroke
				(width 0.1)
				(type default)
			)
			(layer "F.Fab")
		)
		(fp_line
			(start -0.12065 -0.2794)
			(end 0.12065 -0.2794)
			(stroke
				(width 0.1)
				(type default)
			)
			(layer "F.Fab")
		)
		(fp_line
			(start -0.12065 -0.305054)
			(end -0.12065 -0.2794)
			(stroke
				(width 0.1)
				(type default)
			)
			(layer "F.Fab")
		)
		(fp_line
			(start -0.67945 0.3048)
			(end -0.67945 -0.305054)
			(stroke
				(width 0.1)
				(type default)
			)
			(layer "F.Fab")
		)
		(fp_line
			(start -0.67945 -0.305054)
			(end -0.12065 -0.305054)
			(stroke
				(width 0.1)
				(type default)
			)
			(layer "F.Fab")
		)
		(pad "1" smd circle
			(at -0.40005 0 180)
			(size 0 0)
			(layers "F.Cu" "F.Mask" "F.Paste")
			(net "LED_POSTCODE_3")
		)
		(pad "2" smd circle
			(at 0.40005 0 180)
			(size 0 0)
			(layers "F.Cu" "F.Mask" "F.Paste")
			(net "LED_POSTCODE_3_R")
		)
	)
)
